# S9S_MB_2U (Grand Teton) — schematic netlist excerpt (pin names and nets, part order shuffled) for the footprints in the layout excerpt that follows; sources: Cadence DE-HDL packaged netlist, KiCad conversion of 03242023_DA0F0TMBIJ0_F0T_Motherboard_J_brd_V01_OCP.brd

R2978  Q_RES  1K 1% EMPTY  pkg 0402LF  page 195 : A = FAB_REV_ID0 ; B = GND
R2696  Q_RES  1K 1% CHIP  pkg 0402LF  page 227 : A = TCA9539_0_ADD0 ; B = GND

(kicad_pcb
	(version 20260206)
	(generator "pcbnew")
	(generator_version "10.0")
	(general
		(thickness 1.6)
		(legacy_teardrops no)
	)
	(paper "A4")
	(title_block
		(title "03242023_DA0F0TMBIJ0_F0T_Motherboard_J_brd_V01_OCP.brd")
		(comment 1 "Grand Teton / footprints 2734-2735 of 6105")
	)
	(layers
		(0 "F.Cu" signal "TOP")
		(4 "In1.Cu" signal "GND")
		(6 "In2.Cu" signal "IN1")
		(8 "In3.Cu" signal "GND1")
		(10 "In4.Cu" signal "IN2")
		(12 "In5.Cu" signal "GND2")
		(14 "In6.Cu" signal "IN3")
		(16 "In7.Cu" signal "GND3")
		(18 "In8.Cu" signal "VCC")
		(20 "In9.Cu" signal "VCC1")
		(22 "In10.Cu" signal "GND4")
		(24 "In11.Cu" signal "IN4")
		(26 "In12.Cu" signal "GND5")
		(28 "In13.Cu" signal "IN5")
		(30 "In14.Cu" signal "GND6")
		(32 "In15.Cu" signal "IN6")
		(34 "In16.Cu" signal "GND7")
		(2 "B.Cu" signal "BOTTOM")
		(9 "F.Adhes" user "F.Adhesive")
		(11 "B.Adhes" user "B.Adhesive")
		(13 "F.Paste" user "Package Geometry/Pastemask Top")
		(15 "B.Paste" user "Package Geometry/Pastemask Bottom")
		(5 "F.SilkS" user "Ref Des/Silkscreen Top")
		(7 "B.SilkS" user "Ref Des/Silkscreen Bottom")
		(1 "F.Mask" user "Board Geometry/Soldermask Top")
		(3 "B.Mask" user "Board Geometry/Soldermask Bottom")
		(17 "Dwgs.User" user "User.Drawings")
		(19 "Cmts.User" user "User.Comments")
		(21 "Eco1.User" user "User.Eco1")
		(23 "Eco2.User" user "User.Eco2")
		(25 "Edge.Cuts" user "Board Geometry/Outline")
		(27 "Margin" user)
		(31 "F.CrtYd" user "Package Geometry/Place Bound Top")
		(29 "B.CrtYd" user "Package Geometry/Place Bound Bottom")
		(35 "F.Fab" user "Ref Des/Assembly Top")
		(33 "B.Fab" user "Ref Des/Assembly Bottom")
	)
	(footprint ""
		(layer "F.Cu")
		(at 299.02023 -52.368196 180)
		(property "Reference" "R2978"
			(at 0 0 180)
			(layer "F.SilkS")
			(hide yes)
			(effects
				(font
					(size 1.27 1.27)
				)
			)
		)
		(property "Value" ""
			(at 0 0 180)
			(layer "F.Fab")
			(effects
				(font
					(size 1.27 1.27)
				)
			)
		)
		(duplicate_pad_numbers_are_jumpers no)
		(fp_line
			(start 0.7874 0.4064)
			(end -0.7874 0.4064)
			(stroke
				(width 0.1524)
				(type default)
			)
			(layer "F.SilkS")
		)
		(fp_line
			(start 0.7874 -0.4064)
			(end 0.7874 0.4064)
			(stroke
				(width 0.1524)
				(type default)
			)
			(layer "F.SilkS")
		)
		(fp_line
			(start -0.7874 0.4064)
			(end -0.7874 -0.4064)
			(stroke
				(width 0.1524)
				(type default)
			)
			(layer "F.SilkS")
		)
		(fp_line
			(start -0.7874 -0.4064)
			(end 0.7874 -0.4064)
			(stroke
				(width 0.1524)
				(type default)
			)
			(layer "F.SilkS")
		)
		(fp_line
			(start 0.67945 0.3048)
			(end 0.120396 0.3048)
			(stroke
				(width 0.1)
				(type default)
			)
			(layer "F.Fab")
		)
		(fp_line
			(start 0.67945 -0.3048)
			(end 0.67945 0.3048)
			(stroke
				(width 0.1)
				(type default)
			)
			(layer "F.Fab")
		)
		(fp_line
			(start 0.12065 -0.2794)
			(end 0.12065 -0.3048)
			(stroke
				(width 0.1)
				(type default)
			)
			(layer "F.Fab")
		)
		(fp_line
			(start 0.12065 -0.3048)
			(end 0.67945 -0.3048)
			(stroke
				(width 0.1)
				(type default)
			)
			(layer "F.Fab")
		)
		(fp_line
			(start 0.120396 0.3048)
			(end 0.120396 0.2794)
			(stroke
				(width 0.1)
				(type default)
			)
			(layer "F.Fab")
		)
		(fp_line
			(start 0.120396 0.2794)
			(end -0.12065 0.2794)
			(stroke
				(width 0.1)
				(type default)
			)
			(layer "F.Fab")
		)
		(fp_line
			(start -0.12065 0.3048)
			(end -0.67945 0.3048)
			(stroke
				(width 0.1)
				(type default)
			)
			(layer "F.Fab")
		)
		(fp_line
			(start -0.12065 0.2794)
			(end -0.12065 0.3048)
			(stroke
				(width 0.1)
				(type default)
			)
			(layer "F.Fab")
		)
		(fp_line
			(start -0.12065 -0.2794)
			(end 0.12065 -0.2794)
			(stroke
				(width 0.1)
				(type default)
			)
			(layer "F.Fab")
		)
		(fp_line
			(start -0.12065 -0.305054)
			(end -0.12065 -0.2794)
			(stroke
				(width 0.1)
				(type default)
			)
			(layer "F.Fab")
		)
		(fp_line
			(start -0.67945 0.3048)
			(end -0.67945 -0.305054)
			(stroke
				(width 0.1)
				(type default)
			)
			(layer "F.Fab")
		)
		(fp_line
			(start -0.67945 -0.305054)
			(end -0.12065 -0.305054)
			(stroke
				(width 0.1)
				(type default)
			)
			(layer "F.Fab")
		)
		(pad "1" smd circle
			(at -0.40005 0 180)
			(size 0 0)
			(layers "F.Cu" "F.Mask" "F.Paste")
			(net "FAB_REV_ID0")
		)
		(pad "2" smd circle
			(at 0.40005 0 180)
			(size 0 0)
			(layers "F.Cu" "F.Mask" "F.Paste")
			(net "GND")
		)
	)
	(footprint ""
		(layer "F.Cu")
		(at 13.6398 -425.7548 90)
		(property "Reference" "R2696"
			(at 0 0 90)
			(layer "F.SilkS")
			(hide yes)
			(effects
				(font
					(size 1.27 1.27)
				)
			)
		)
		(property "Value" ""
			(at 0 0 90)
			(layer "F.Fab")
			(effects
				(font
					(size 1.27 1.27)
				)
			)
		)
		(duplicate_pad_numbers_are_jumpers no)
		(fp_line
			(start 0.7874 -0.4064)
			(end 0.7874 0.4064)
			(stroke
				(width 0.1524)
				(type default)
			)
			(layer "F.SilkS")
		)
		(fp_line
			(start -0.7874 -0.4064)
			(end 0.7874 -0.4064)
			(stroke
				(width 0.1524)
				(type default)
			)
			(layer "F.SilkS")
		)
		(fp_line
			(start 0.7874 0.4064)
			(end -0.7874 0.4064)
			(stroke
				(width 0.1524)
				(type default)
			)
			(layer "F.SilkS")
		)
		(fp_line
			(start -0.7874 0.4064)
			(end -0.7874 -0.4064)
			(stroke
				(width 0.1524)
				(type default)
			)
			(layer "F.SilkS")
		)
		(fp_line
			(start -0.12065 -0.305054)
			(end -0.12065 -0.2794)
			(stroke
				(width 0.1)
				(type default)
			)
			(layer "F.Fab")
		)
		(fp_line
			(start -0.67945 -0.305054)
			(end -0.12065 -0.305054)
			(stroke
				(width 0.1)
				(type default)
			)
			(layer "F.Fab")
		)
		(fp_line
			(start 0.67945 -0.3048)
			(end 0.67945 0.3048)
			(stroke
				(width 0.1)
				(type default)
			)
			(layer "F.Fab")
		)
		(fp_line
			(start 0.12065 -0.3048)
			(end 0.67945 -0.3048)
			(stroke
				(width 0.1)
				(type default)
			)
			(layer "F.Fab")
		)
		(fp_line
			(start 0.12065 -0.2794)
			(end 0.12065 -0.3048)
			(stroke
				(width 0.1)
				(type default)
			)
			(layer "F.Fab")
		)
		(fp_line
			(start -0.12065 -0.2794)
			(end 0.12065 -0.2794)
			(stroke
				(width 0.1)
				(type default)
			)
			(layer "F.Fab")
		)
		(fp_line
			(start 0.120396 0.2794)
			(end -0.12065 0.2794)
			(stroke
				(width 0.1)
				(type default)
			)
			(layer "F.Fab")
		)
		(fp_line
			(start -0.12065 0.2794)
			(end -0.12065 0.3048)
			(stroke
				(width 0.1)
				(type default)
			)
			(layer "F.Fab")
		)
		(fp_line
			(start 0.67945 0.3048)
			(end 0.120396 0.3048)
			(stroke
				(width 0.1)
				(type default)
			)
			(layer "F.Fab")
		)
		(fp_line
			(start 0.120396 0.3048)
			(end 0.120396 0.2794)
			(stroke
				(width 0.1)
				(type default)
			)
			(layer "F.Fab")
		)
		(fp_line
			(start -0.12065 0.3048)
			(end -0.67945 0.3048)
			(stroke
				(width 0.1)
				(type default)
			)
			(layer "F.Fab")
		)
		(fp_line
			(start -0.67945 0.3048)
			(end -0.67945 -0.305054)
			(stroke
				(width 0.1)
				(type default)
			)
			(layer "F.Fab")
		)
		(pad "1" smd circle
			(at -0.40005 0 90)
			(size 0 0)
			(layers "F.Cu" "F.Mask" "F.Paste")
			(net "TCA9539_0_ADD0")
		)
		(pad "2" smd circle
			(at 0.40005 0 90)
			(size 0 0)
			(layers "F.Cu" "F.Mask" "F.Paste")
			(net "GND")
		)
	)
)
